# T6G (Grand Teton) — schematic netlist excerpt (pin names and nets, part order shuffled) for the footprints in the layout excerpt that follows; sources: Cadence DE-HDL packaged netlist, KiCad conversion of 04192023_DAF0TMB3IC0_F0TG_MB_C_brd_V02_OCP.brd

R3713  Q_RES  0 5% CHIP  pkg 0402LF  page 252 : A = SMB_VR_3V3AUX_SCL_R6 ; B = SMB_VR_3V3AUX_SCL

(kicad_pcb
	(version 20260206)
	(generator "pcbnew")
	(generator_version "10.0")
	(general
		(thickness 1.6)
		(legacy_teardrops no)
	)
	(paper "A4")
	(title_block
		(title "04192023_DAF0TMB3IC0_F0TG_MB_C_brd_V02_OCP.brd")
		(comment 1 "Grand Teton / footprints 654-654 of 8354")
	)
	(layers
		(0 "F.Cu" signal "TOP")
		(4 "In1.Cu" signal "GND")
		(6 "In2.Cu" signal "IN1")
		(8 "In3.Cu" signal "GND1")
		(10 "In4.Cu" signal "IN2")
		(12 "In5.Cu" signal "GND2")
		(14 "In6.Cu" signal "IN3")
		(16 "In7.Cu" signal "GND3")
		(18 "In8.Cu" signal "VCC")
		(20 "In9.Cu" signal "VCC1")
		(22 "In10.Cu" signal "GND4")
		(24 "In11.Cu" signal "IN4")
		(26 "In12.Cu" signal "GND5")
		(28 "In13.Cu" signal "IN5")
		(30 "In14.Cu" signal "GND6")
		(32 "In15.Cu" signal "IN6")
		(34 "In16.Cu" signal "GND7")
		(2 "B.Cu" signal "BOTTOM")
		(9 "F.Adhes" user "F.Adhesive")
		(11 "B.Adhes" user "B.Adhesive")
		(13 "F.Paste" user "Package Geometry/Pastemask Top")
		(15 "B.Paste" user "Package Geometry/Pastemask Bottom")
		(5 "F.SilkS" user "Ref Des/Silkscreen Top")
		(7 "B.SilkS" user "Ref Des/Silkscreen Bottom")
		(1 "F.Mask" user "Board Geometry/Soldermask Top")
		(3 "B.Mask" user "Board Geometry/Soldermask Bottom")
		(17 "Dwgs.User" user "User.Drawings")
		(19 "Cmts.User" user "User.Comments")
		(21 "Eco1.User" user "User.Eco1")
		(23 "Eco2.User" user "User.Eco2")
		(25 "Edge.Cuts" user "Board Geometry/Outline")
		(27 "Margin" user)
		(31 "F.CrtYd" user "Package Geometry/Place Bound Top")
		(29 "B.CrtYd" user "Package Geometry/Place Bound Bottom")
		(35 "F.Fab" user "Ref Des/Assembly Top")
		(33 "B.Fab" user "Ref Des/Assembly Bottom")
	)
	(footprint ""
		(layer "F.Cu")
		(at 257.242056 -120.94337 180)
		(property "Reference" "R3713"
			(at 0 0 180)
			(layer "F.SilkS")
			(hide yes)
			(effects
				(font
					(size 1.27 1.27)
				)
			)
		)
		(property "Value" ""
			(at 0 0 180)
			(layer "F.Fab")
			(effects
				(font
					(size 1.27 1.27)
				)
			)
		)
		(duplicate_pad_numbers_are_jumpers no)
		(fp_line
			(start 0.7874 0.4064)
			(end -0.7874 0.4064)
			(stroke
				(width 0.1524)
				(type default)
			)
			(layer "F.SilkS")
		)
		(fp_line
			(start 0.7874 -0.4064)
			(end 0.7874 0.4064)
			(stroke
				(width 0.1524)
				(type default)
			)
			(layer "F.SilkS")
		)
		(fp_line
			(start -0.7874 0.4064)
			(end -0.7874 -0.4064)
			(stroke
				(width 0.1524)
				(type default)
			)
			(layer "F.SilkS")
		)
		(fp_line
			(start -0.7874 -0.4064)
			(end 0.7874 -0.4064)
			(stroke
				(width 0.1524)
				(type default)
			)
			(layer "F.SilkS")
		)
		(fp_line
			(start 0.67945 0.3048)
			(end 0.120396 0.3048)
			(stroke
				(width 0.1)
				(type default)
			)
			(layer "F.Fab")
		)
		(fp_line
			(start 0.67945 -0.3048)
			(end 0.67945 0.3048)
			(stroke
				(width 0.1)
				(type default)
			)
			(layer "F.Fab")
		)
		(fp_line
			(start 0.12065 -0.2794)
			(end 0.12065 -0.3048)
			(stroke
				(width 0.1)
				(type default)
			)
			(layer "F.Fab")
		)
		(fp_line
			(start 0.12065 -0.3048)
			(end 0.67945 -0.3048)
			(stroke
				(width 0.1)
				(type default)
			)
			(layer "F.Fab")
		)
		(fp_line
			(start 0.120396 0.3048)
			(end 0.120396 0.2794)
			(stroke
				(width 0.1)
				(type default)
			)
			(layer "F.Fab")
		)
		(fp_line
			(start 0.120396 0.2794)
			(end -0.12065 0.2794)
			(stroke
				(width 0.1)
				(type default)
			)
			(layer "F.Fab")
		)
		(fp_line
			(start -0.12065 0.3048)
			(end -0.67945 0.3048)
			(stroke
				(width 0.1)
				(type default)
			)
			(layer "F.Fab")
		)
		(fp_line
			(start -0.12065 0.2794)
			(end -0.12065 0.3048)
			(stroke
				(width 0.1)
				(type default)
			)
			(layer "F.Fab")
		)
		(fp_line
			(start -0.12065 -0.2794)
			(end 0.12065 -0.2794)
			(stroke
				(width 0.1)
				(type default)
			)
			(layer "F.Fab")
		)
		(fp_line
			(start -0.12065 -0.305054)
			(end -0.12065 -0.2794)
			(stroke
				(width 0.1)
				(type default)
			)
			(layer "F.Fab")
		)
		(fp_line
			(start -0.67945 0.3048)
			(end -0.67945 -0.305054)
			(stroke
				(width 0.1)
				(type default)
			)
			(layer "F.Fab")
		)
		(fp_line
			(start -0.67945 -0.305054)
			(end -0.12065 -0.305054)
			(stroke
				(width 0.1)
				(type default)
			)
			(layer "F.Fab")
		)
		(pad "1" smd circle
			(at -0.40005 0 180)
			(size 0 0)
			(layers "F.Cu" "F.Mask" "F.Paste")
			(net "SMB_VR_3V3AUX_SCL_R6")
		)
		(pad "2" smd circle
			(at 0.40005 0 180)
			(size 0 0)
			(layers "F.Cu" "F.Mask" "F.Paste")
			(net "SMB_VR_3V3AUX_SCL")
		)
	)
)
